# SCM (Grand Teton) — schematic netlist excerpt (pin names and nets, part order shuffled) for the footprints in the layout excerpt that follows; sources: Cadence DE-HDL packaged netlist, KiCad conversion of 12092022_DA0F0TMDCD0_F0T_Management_Board_D_brd_V3_OCP.brd

C281  Q_CAP  0.01UF 50V 10% EMPTY  pkg C0402  page 41 : A = VCCIO1 ; B = GND
R83  Q_RES  0 5% CHIP  pkg 0402LF  page 28 : A = FM_UART_SEL_N ; B = FM_UART_SWITCH_N

(kicad_pcb
	(version 20260206)
	(generator "pcbnew")
	(generator_version "10.0")
	(general
		(thickness 1.6)
		(legacy_teardrops no)
	)
	(paper "A4")
	(title_block
		(title "12092022_DA0F0TMDCD0_F0T_Management_Board_D_brd_V3_OCP.brd")
		(comment 1 "Grand Teton / footprints 1064-1065 of 1440")
	)
	(layers
		(0 "F.Cu" signal "TOP")
		(4 "In1.Cu" signal "GND")
		(6 "In2.Cu" signal "IN1")
		(8 "In3.Cu" signal "GND1")
		(10 "In4.Cu" signal "IN2")
		(12 "In5.Cu" signal "VCC")
		(14 "In6.Cu" signal "VCC1")
		(16 "In7.Cu" signal "IN3")
		(18 "In8.Cu" signal "GND2")
		(20 "In9.Cu" signal "IN4")
		(22 "In10.Cu" signal "GND3")
		(2 "B.Cu" signal "BOTTOM")
		(9 "F.Adhes" user "F.Adhesive")
		(11 "B.Adhes" user "B.Adhesive")
		(13 "F.Paste" user "Package Geometry/Pastemask Top")
		(15 "B.Paste" user "Package Geometry/Pastemask Bottom")
		(5 "F.SilkS" user "Ref Des/Silkscreen Top")
		(7 "B.SilkS" user "Ref Des/Silkscreen Bottom")
		(1 "F.Mask" user "Board Geometry/Soldermask Top")
		(3 "B.Mask" user "Board Geometry/Soldermask Bottom")
		(17 "Dwgs.User" user "User.Drawings")
		(19 "Cmts.User" user "User.Comments")
		(21 "Eco1.User" user "User.Eco1")
		(23 "Eco2.User" user "User.Eco2")
		(25 "Edge.Cuts" user "Board Geometry/Outline")
		(27 "Margin" user)
		(31 "F.CrtYd" user "Package Geometry/Place Bound Top")
		(29 "B.CrtYd" user "Package Geometry/Place Bound Bottom")
		(35 "F.Fab" user "Ref Des/Assembly Top")
		(33 "B.Fab" user "Ref Des/Assembly Bottom")
	)
	(footprint ""
		(layer "B.Cu")
		(at 18.259298 -95.587058 180)
		(property "Reference" "C281"
			(at 0 0 0)
			(layer "B.SilkS")
			(hide yes)
			(effects
				(font
					(size 1.27 1.27)
				)
				(justify mirror)
			)
		)
		(property "Value" ""
			(at 0 0 0)
			(layer "B.Fab")
			(effects
				(font
					(size 1.27 1.27)
				)
				(justify mirror)
			)
		)
		(duplicate_pad_numbers_are_jumpers no)
		(fp_line
			(start 0.69215 0.2921)
			(end 0.69215 -0.2921)
			(stroke
				(width 0.1524)
				(type default)
			)
			(layer "B.SilkS")
		)
		(fp_line
			(start 0.69215 -0.2921)
			(end -0.69215 -0.2921)
			(stroke
				(width 0.1524)
				(type default)
			)
			(layer "B.SilkS")
		)
		(fp_line
			(start -0.69215 0.2921)
			(end 0.69215 0.2921)
			(stroke
				(width 0.1524)
				(type default)
			)
			(layer "B.SilkS")
		)
		(fp_line
			(start -0.69215 -0.2921)
			(end -0.69215 0.2921)
			(stroke
				(width 0.1524)
				(type default)
			)
			(layer "B.SilkS")
		)
		(fp_line
			(start 0.51435 0.2794)
			(end 0.51435 -0.2794)
			(stroke
				(width 0.1)
				(type default)
			)
			(layer "B.Fab")
		)
		(fp_line
			(start 0.51435 -0.2794)
			(end -0.51435 -0.2794)
			(stroke
				(width 0.1)
				(type default)
			)
			(layer "B.Fab")
		)
		(fp_line
			(start -0.51435 0.2794)
			(end 0.51435 0.2794)
			(stroke
				(width 0.1)
				(type default)
			)
			(layer "B.Fab")
		)
		(fp_line
			(start -0.51435 -0.2794)
			(end -0.51435 0.2794)
			(stroke
				(width 0.1)
				(type default)
			)
			(layer "B.Fab")
		)
		(pad "1" smd circle
			(at 0.40005 0)
			(size 0 0)
			(layers "B.Cu" "B.Mask" "B.Paste")
			(net "VCCIO1")
		)
		(pad "2" smd circle
			(at -0.40005 0)
			(size 0 0)
			(layers "B.Cu" "B.Mask" "B.Paste")
			(net "GND")
		)
		(zone
			(layer "B.Cu")
			(hatch none 0.5)
			(connect_pads
				(clearance 0)
			)
			(min_thickness 0.25)
			(keepout
				(tracks not_allowed)
				(vias allowed)
				(pads allowed)
				(copperpour not_allowed)
				(footprints allowed)
			)
			(placement
				(enabled no)
				(sheetname "")
			)
			(fill
				(thermal_gap 0.5)
				(thermal_bridge_width 0.5)
				(island_removal_mode 0)
			)
			(polygon
				(pts
					(xy 18.068798 -95.674688) (xy 18.160238 -95.732854) (xy 18.359628 -95.732854) (xy 18.449798 -95.674688)
					(xy 18.449798 -95.499428) (xy 18.359628 -95.441008) (xy 18.160238 -95.441008) (xy 18.068798 -95.499174)
				)
			)
		)
	)
	(footprint ""
		(layer "B.Cu")
		(at 51.2445 -92.2655 180)
		(property "Reference" "R83"
			(at 0 0 0)
			(layer "B.SilkS")
			(hide yes)
			(effects
				(font
					(size 1.27 1.27)
				)
				(justify mirror)
			)
		)
		(property "Value" ""
			(at 0 0 0)
			(layer "B.Fab")
			(effects
				(font
					(size 1.27 1.27)
				)
				(justify mirror)
			)
		)
		(duplicate_pad_numbers_are_jumpers no)
		(fp_line
			(start 0.7874 0.4064)
			(end 0.7874 -0.4064)
			(stroke
				(width 0.1524)
				(type default)
			)
			(layer "B.SilkS")
		)
		(fp_line
			(start 0.7874 -0.4064)
			(end -0.7874 -0.4064)
			(stroke
				(width 0.1524)
				(type default)
			)
			(layer "B.SilkS")
		)
		(fp_line
			(start -0.7874 0.4064)
			(end 0.7874 0.4064)
			(stroke
				(width 0.1524)
				(type default)
			)
			(layer "B.SilkS")
		)
		(fp_line
			(start -0.7874 -0.4064)
			(end -0.7874 0.4064)
			(stroke
				(width 0.1524)
				(type default)
			)
			(layer "B.SilkS")
		)
		(fp_line
			(start 0.67945 0.3048)
			(end 0.67945 -0.305054)
			(stroke
				(width 0.1)
				(type default)
			)
			(layer "B.Fab")
		)
		(fp_line
			(start 0.67945 -0.305054)
			(end 0.12065 -0.305054)
			(stroke
				(width 0.1)
				(type default)
			)
			(layer "B.Fab")
		)
		(fp_line
			(start 0.12065 0.3048)
			(end 0.67945 0.3048)
			(stroke
				(width 0.1)
				(type default)
			)
			(layer "B.Fab")
		)
		(fp_line
			(start 0.12065 0.2794)
			(end 0.12065 0.3048)
			(stroke
				(width 0.1)
				(type default)
			)
			(layer "B.Fab")
		)
		(fp_line
			(start 0.12065 -0.2794)
			(end -0.12065 -0.2794)
			(stroke
				(width 0.1)
				(type default)
			)
			(layer "B.Fab")
		)
		(fp_line
			(start 0.12065 -0.305054)
			(end 0.12065 -0.2794)
			(stroke
				(width 0.1)
				(type default)
			)
			(layer "B.Fab")
		)
		(fp_line
			(start -0.120396 0.3048)
			(end -0.120396 0.2794)
			(stroke
				(width 0.1)
				(type default)
			)
			(layer "B.Fab")
		)
		(fp_line
			(start -0.120396 0.2794)
			(end 0.12065 0.2794)
			(stroke
				(width 0.1)
				(type default)
			)
			(layer "B.Fab")
		)
		(fp_line
			(start -0.12065 -0.2794)
			(end -0.12065 -0.3048)
			(stroke
				(width 0.1)
				(type default)
			)
			(layer "B.Fab")
		)
		(fp_line
			(start -0.12065 -0.3048)
			(end -0.67945 -0.3048)
			(stroke
				(width 0.1)
				(type default)
			)
			(layer "B.Fab")
		)
		(fp_line
			(start -0.67945 0.3048)
			(end -0.120396 0.3048)
			(stroke
				(width 0.1)
				(type default)
			)
			(layer "B.Fab")
		)
		(fp_line
			(start -0.67945 -0.3048)
			(end -0.67945 0.3048)
			(stroke
				(width 0.1)
				(type default)
			)
			(layer "B.Fab")
		)
		(pad "1" smd circle
			(at 0.40005 0)
			(size 0 0)
			(layers "B.Cu" "B.Mask" "B.Paste")
			(net "FM_UART_SEL_N")
		)
		(pad "2" smd circle
			(at -0.40005 0)
			(size 0 0)
			(layers "B.Cu" "B.Mask" "B.Paste")
			(net "FM_UART_SWITCH_N")
		)
	)
)
